(kicad_pcb
	(version 20260206)
	(generator "pcbnew")
	(generator_version "10.0")
	(general
		(thickness 1.6)
		(legacy_teardrops no)
	)
	(paper "A4")
	(title_block
		(title "01162023_DA0F0TEBIF0_F0T_Expander_BD_F_brd_V02_OCP.brd")
		(comment 1 "Grand Teton / footprints 7385-7393 of 9728")
	)
	(layers
		(0 "F.Cu" signal "TOP")
		(4 "In1.Cu" signal "GND")
		(6 "In2.Cu" signal "VCC")
		(8 "In3.Cu" signal "VCC1")
		(10 "In4.Cu" signal "GND1")
		(12 "In5.Cu" signal "IN1")
		(14 "In6.Cu" signal "GND2")
		(16 "In7.Cu" signal "IN2")
		(18 "In8.Cu" signal "GND3")
		(20 "In9.Cu" signal "IN3")
		(22 "In10.Cu" signal "GND4")
		(24 "In11.Cu" signal "IN4")
		(26 "In12.Cu" signal "GND5")
		(28 "In13.Cu" signal "IN5")
		(30 "In14.Cu" signal "GND6")
		(32 "In15.Cu" signal "IN6")
		(34 "In16.Cu" signal "GND7")
		(2 "B.Cu" signal "BOTTOM")
		(9 "F.Adhes" user "F.Adhesive")
		(11 "B.Adhes" user "B.Adhesive")
		(13 "F.Paste" user "Package Geometry/Pastemask Top")
		(15 "B.Paste" user "Package Geometry/Pastemask Bottom")
		(5 "F.SilkS" user "Ref Des/Silkscreen Top")
		(7 "B.SilkS" user "Ref Des/Silkscreen Bottom")
		(1 "F.Mask" user "Board Geometry/Soldermask Top")
		(3 "B.Mask" user "Board Geometry/Soldermask Bottom")
		(17 "Dwgs.User" user "User.Drawings")
		(19 "Cmts.User" user "User.Comments")
		(21 "Eco1.User" user "User.Eco1")
		(23 "Eco2.User" user "User.Eco2")
		(25 "Edge.Cuts" user "Board Geometry/Outline")
		(27 "Margin" user)
		(31 "F.CrtYd" user "Package Geometry/Place Bound Top")
		(29 "B.CrtYd" user "Package Geometry/Place Bound Bottom")
		(35 "F.Fab" user "Ref Des/Assembly Top")
		(33 "B.Fab" user "Ref Des/Assembly Bottom")
	)
	(footprint ""
		(layer "B.Cu")
		(at 71.755 -98.552)
		(property "Reference" "R53"
			(at 0 0 0)
			(layer "B.SilkS")
			(hide yes)
			(effects
				(font
					(size 1.27 1.27)
				)
				(justify mirror)
			)
		)
		(property "Value" ""
			(at 0 0 0)
			(layer "B.Fab")
			(effects
				(font
					(size 1.27 1.27)
				)
				(justify mirror)
			)
		)
		(duplicate_pad_numbers_are_jumpers no)
		(fp_line
			(start -0.7874 -0.4064)
			(end -0.7874 0.4064)
			(stroke
				(width 0.1524)
				(type default)
			)
			(layer "B.SilkS")
		)
		(fp_line
			(start -0.7874 0.4064)
			(end 0.7874 0.4064)
			(stroke
				(width 0.1524)
				(type default)
			)
			(layer "B.SilkS")
		)
		(fp_line
			(start 0.7874 -0.4064)
			(end -0.7874 -0.4064)
			(stroke
				(width 0.1524)
				(type default)
			)
			(layer "B.SilkS")
		)
		(fp_line
			(start 0.7874 0.4064)
			(end 0.7874 -0.4064)
			(stroke
				(width 0.1524)
				(type default)
			)
			(layer "B.SilkS")
		)
		(fp_line
			(start -0.67945 -0.3048)
			(end -0.67945 0.3048)
			(stroke
				(width 0.1)
				(type default)
			)
			(layer "B.Fab")
		)
		(fp_line
			(start -0.67945 0.3048)
			(end -0.120396 0.3048)
			(stroke
				(width 0.1)
				(type default)
			)
			(layer "B.Fab")
		)
		(fp_line
			(start -0.12065 -0.3048)
			(end -0.67945 -0.3048)
			(stroke
				(width 0.1)
				(type default)
			)
			(layer "B.Fab")
		)
		(fp_line
			(start -0.12065 -0.2794)
			(end -0.12065 -0.3048)
			(stroke
				(width 0.1)
				(type default)
			)
			(layer "B.Fab")
		)
		(fp_line
			(start -0.120396 0.2794)
			(end 0.12065 0.2794)
			(stroke
				(width 0.1)
				(type default)
			)
			(layer "B.Fab")
		)
		(fp_line
			(start -0.120396 0.3048)
			(end -0.120396 0.2794)
			(stroke
				(width 0.1)
				(type default)
			)
			(layer "B.Fab")
		)
		(fp_line
			(start 0.12065 -0.305054)
			(end 0.12065 -0.2794)
			(stroke
				(width 0.1)
				(type default)
			)
			(layer "B.Fab")
		)
		(fp_line
			(start 0.12065 -0.2794)
			(end -0.12065 -0.2794)
			(stroke
				(width 0.1)
				(type default)
			)
			(layer "B.Fab")
		)
		(fp_line
			(start 0.12065 0.2794)
			(end 0.12065 0.3048)
			(stroke
				(width 0.1)
				(type default)
			)
			(layer "B.Fab")
		)
		(fp_line
			(start 0.12065 0.3048)
			(end 0.67945 0.3048)
			(stroke
				(width 0.1)
				(type default)
			)
			(layer "B.Fab")
		)
		(fp_line
			(start 0.67945 -0.305054)
			(end 0.12065 -0.305054)
			(stroke
				(width 0.1)
				(type default)
			)
			(layer "B.Fab")
		)
		(fp_line
			(start 0.67945 0.3048)
			(end 0.67945 -0.305054)
			(stroke
				(width 0.1)
				(type default)
			)
			(layer "B.Fab")
		)
		(pad "1" smd circle
			(at 0.40005 0 180)
			(size 0 0)
			(layers "B.Cu" "B.Mask" "B.Paste")
			(net "NIC1_MAIN_PWR_EN_R")
		)
		(pad "2" smd circle
			(at -0.40005 0 180)
			(size 0 0)
			(layers "B.Cu" "B.Mask" "B.Paste")
			(net "NIC1_MAIN_PWR_EN")
		)
	)
	(footprint ""
		(layer "B.Cu")
		(at 211.810092 -368.406172 -90)
		(property "Reference" "PR8"
			(at 0 0 90)
			(layer "B.SilkS")
			(hide yes)
			(effects
				(font
					(size 1.27 1.27)
				)
				(justify mirror)
			)
		)
		(property "Value" ""
			(at 0 0 90)
			(layer "B.Fab")
			(effects
				(font
					(size 1.27 1.27)
				)
				(justify mirror)
			)
		)
		(duplicate_pad_numbers_are_jumpers no)
		(fp_line
			(start -0.7874 0.4064)
			(end 0.7874 0.4064)
			(stroke
				(width 0.1524)
				(type default)
			)
			(layer "B.SilkS")
		)
		(fp_line
			(start 0.7874 0.4064)
			(end 0.7874 -0.4064)
			(stroke
				(width 0.1524)
				(type default)
			)
			(layer "B.SilkS")
		)
		(fp_line
			(start -0.7874 -0.4064)
			(end -0.7874 0.4064)
			(stroke
				(width 0.1524)
				(type default)
			)
			(layer "B.SilkS")
		)
		(fp_line
			(start 0.7874 -0.4064)
			(end -0.7874 -0.4064)
			(stroke
				(width 0.1524)
				(type default)
			)
			(layer "B.SilkS")
		)
		(fp_line
			(start -0.67945 0.3048)
			(end -0.120396 0.3048)
			(stroke
				(width 0.1)
				(type default)
			)
			(layer "B.Fab")
		)
		(fp_line
			(start -0.120396 0.3048)
			(end -0.120396 0.2794)
			(stroke
				(width 0.1)
				(type default)
			)
			(layer "B.Fab")
		)
		(fp_line
			(start 0.12065 0.3048)
			(end 0.67945 0.3048)
			(stroke
				(width 0.1)
				(type default)
			)
			(layer "B.Fab")
		)
		(fp_line
			(start 0.67945 0.3048)
			(end 0.67945 -0.305054)
			(stroke
				(width 0.1)
				(type default)
			)
			(layer "B.Fab")
		)
		(fp_line
			(start -0.120396 0.2794)
			(end 0.12065 0.2794)
			(stroke
				(width 0.1)
				(type default)
			)
			(layer "B.Fab")
		)
		(fp_line
			(start 0.12065 0.2794)
			(end 0.12065 0.3048)
			(stroke
				(width 0.1)
				(type default)
			)
			(layer "B.Fab")
		)
		(fp_line
			(start -0.12065 -0.2794)
			(end -0.12065 -0.3048)
			(stroke
				(width 0.1)
				(type default)
			)
			(layer "B.Fab")
		)
		(fp_line
			(start 0.12065 -0.2794)
			(end -0.12065 -0.2794)
			(stroke
				(width 0.1)
				(type default)
			)
			(layer "B.Fab")
		)
		(fp_line
			(start -0.67945 -0.3048)
			(end -0.67945 0.3048)
			(stroke
				(width 0.1)
				(type default)
			)
			(layer "B.Fab")
		)
		(fp_line
			(start -0.12065 -0.3048)
			(end -0.67945 -0.3048)
			(stroke
				(width 0.1)
				(type default)
			)
			(layer "B.Fab")
		)
		(fp_line
			(start 0.12065 -0.305054)
			(end 0.12065 -0.2794)
			(stroke
				(width 0.1)
				(type default)
			)
			(layer "B.Fab")
		)
		(fp_line
			(start 0.67945 -0.305054)
			(end 0.12065 -0.305054)
			(stroke
				(width 0.1)
				(type default)
			)
			(layer "B.Fab")
		)
		(pad "1" smd circle
			(at 0.40005 0 90)
			(size 0 0)
			(layers "B.Cu" "B.Mask" "B.Paste")
			(net "HSC_FAULT_N")
		)
		(pad "2" smd circle
			(at -0.40005 0 90)
			(size 0 0)
			(layers "B.Cu" "B.Mask" "B.Paste")
			(net "HSC_VDD")
		)
	)
	(footprint ""
		(layer "B.Cu")
		(at 68.672202 -112.421924)
		(property "Reference" "R60"
			(at 0 0 0)
			(layer "B.SilkS")
			(hide yes)
			(effects
				(font
					(size 1.27 1.27)
				)
				(justify mirror)
			)
		)
		(property "Value" ""
			(at 0 0 0)
			(layer "B.Fab")
			(effects
				(font
					(size 1.27 1.27)
				)
				(justify mirror)
			)
		)
		(duplicate_pad_numbers_are_jumpers no)
		(fp_line
			(start -0.7874 -0.4064)
			(end -0.7874 0.4064)
			(stroke
				(width 0.1524)
				(type default)
			)
			(layer "B.SilkS")
		)
		(fp_line
			(start -0.7874 0.4064)
			(end 0.7874 0.4064)
			(stroke
				(width 0.1524)
				(type default)
			)
			(layer "B.SilkS")
		)
		(fp_line
			(start 0.7874 -0.4064)
			(end -0.7874 -0.4064)
			(stroke
				(width 0.1524)
				(type default)
			)
			(layer "B.SilkS")
		)
		(fp_line
			(start 0.7874 0.4064)
			(end 0.7874 -0.4064)
			(stroke
				(width 0.1524)
				(type default)
			)
			(layer "B.SilkS")
		)
		(fp_line
			(start -0.67945 -0.3048)
			(end -0.67945 0.3048)
			(stroke
				(width 0.1)
				(type default)
			)
			(layer "B.Fab")
		)
		(fp_line
			(start -0.67945 0.3048)
			(end -0.120396 0.3048)
			(stroke
				(width 0.1)
				(type default)
			)
			(layer "B.Fab")
		)
		(fp_line
			(start -0.12065 -0.3048)
			(end -0.67945 -0.3048)
			(stroke
				(width 0.1)
				(type default)
			)
			(layer "B.Fab")
		)
		(fp_line
			(start -0.12065 -0.2794)
			(end -0.12065 -0.3048)
			(stroke
				(width 0.1)
				(type default)
			)
			(layer "B.Fab")
		)
		(fp_line
			(start -0.120396 0.2794)
			(end 0.12065 0.2794)
			(stroke
				(width 0.1)
				(type default)
			)
			(layer "B.Fab")
		)
		(fp_line
			(start -0.120396 0.3048)
			(end -0.120396 0.2794)
			(stroke
				(width 0.1)
				(type default)
			)
			(layer "B.Fab")
		)
		(fp_line
			(start 0.12065 -0.305054)
			(end 0.12065 -0.2794)
			(stroke
				(width 0.1)
				(type default)
			)
			(layer "B.Fab")
		)
		(fp_line
			(start 0.12065 -0.2794)
			(end -0.12065 -0.2794)
			(stroke
				(width 0.1)
				(type default)
			)
			(layer "B.Fab")
		)
		(fp_line
			(start 0.12065 0.2794)
			(end 0.12065 0.3048)
			(stroke
				(width 0.1)
				(type default)
			)
			(layer "B.Fab")
		)
		(fp_line
			(start 0.12065 0.3048)
			(end 0.67945 0.3048)
			(stroke
				(width 0.1)
				(type default)
			)
			(layer "B.Fab")
		)
		(fp_line
			(start 0.67945 -0.305054)
			(end 0.12065 -0.305054)
			(stroke
				(width 0.1)
				(type default)
			)
			(layer "B.Fab")
		)
		(fp_line
			(start 0.67945 0.3048)
			(end 0.67945 -0.305054)
			(stroke
				(width 0.1)
				(type default)
			)
			(layer "B.Fab")
		)
		(pad "1" smd circle
			(at 0.40005 0 180)
			(size 0 0)
			(layers "B.Cu" "B.Mask" "B.Paste")
			(net "P3V3_NIC1")
		)
		(pad "2" smd circle
			(at -0.40005 0 180)
			(size 0 0)
			(layers "B.Cu" "B.Mask" "B.Paste")
			(net "SMB_NIC1_R_SCL")
		)
	)
	(footprint ""
		(layer "B.Cu")
		(at 130.539744 -206.241142 180)
		(property "Reference" "R920"
			(at 0 0 0)
			(layer "B.SilkS")
			(hide yes)
			(effects
				(font
					(size 1.27 1.27)
				)
				(justify mirror)
			)
		)
		(property "Value" ""
			(at 0 0 0)
			(layer "B.Fab")
			(effects
				(font
					(size 1.27 1.27)
				)
				(justify mirror)
			)
		)
		(duplicate_pad_numbers_are_jumpers no)
		(fp_line
			(start 0.7874 0.4064)
			(end 0.7874 -0.4064)
			(stroke
				(width 0.1524)
				(type default)
			)
			(layer "B.SilkS")
		)
		(fp_line
			(start 0.7874 -0.4064)
			(end -0.7874 -0.4064)
			(stroke
				(width 0.1524)
				(type default)
			)
			(layer "B.SilkS")
		)
		(fp_line
			(start -0.7874 0.4064)
			(end 0.7874 0.4064)
			(stroke
				(width 0.1524)
				(type default)
			)
			(layer "B.SilkS")
		)
		(fp_line
			(start -0.7874 -0.4064)
			(end -0.7874 0.4064)
			(stroke
				(width 0.1524)
				(type default)
			)
			(layer "B.SilkS")
		)
		(fp_line
			(start 0.67945 0.3048)
			(end 0.67945 -0.305054)
			(stroke
				(width 0.1)
				(type default)
			)
			(layer "B.Fab")
		)
		(fp_line
			(start 0.67945 -0.305054)
			(end 0.12065 -0.305054)
			(stroke
				(width 0.1)
				(type default)
			)
			(layer "B.Fab")
		)
		(fp_line
			(start 0.12065 0.3048)
			(end 0.67945 0.3048)
			(stroke
				(width 0.1)
				(type default)
			)
			(layer "B.Fab")
		)
		(fp_line
			(start 0.12065 0.2794)
			(end 0.12065 0.3048)
			(stroke
				(width 0.1)
				(type default)
			)
			(layer "B.Fab")
		)
		(fp_line
			(start 0.12065 -0.2794)
			(end -0.12065 -0.2794)
			(stroke
				(width 0.1)
				(type default)
			)
			(layer "B.Fab")
		)
		(fp_line
			(start 0.12065 -0.305054)
			(end 0.12065 -0.2794)
			(stroke
				(width 0.1)
				(type default)
			)
			(layer "B.Fab")
		)
		(fp_line
			(start -0.120396 0.3048)
			(end -0.120396 0.2794)
			(stroke
				(width 0.1)
				(type default)
			)
			(layer "B.Fab")
		)
		(fp_line
			(start -0.120396 0.2794)
			(end 0.12065 0.2794)
			(stroke
				(width 0.1)
				(type default)
			)
			(layer "B.Fab")
		)
		(fp_line
			(start -0.12065 -0.2794)
			(end -0.12065 -0.3048)
			(stroke
				(width 0.1)
				(type default)
			)
			(layer "B.Fab")
		)
		(fp_line
			(start -0.12065 -0.3048)
			(end -0.67945 -0.3048)
			(stroke
				(width 0.1)
				(type default)
			)
			(layer "B.Fab")
		)
		(fp_line
			(start -0.67945 0.3048)
			(end -0.120396 0.3048)
			(stroke
				(width 0.1)
				(type default)
			)
			(layer "B.Fab")
		)
		(fp_line
			(start -0.67945 -0.3048)
			(end -0.67945 0.3048)
			(stroke
				(width 0.1)
				(type default)
			)
			(layer "B.Fab")
		)
		(pad "1" smd circle
			(at 0.40005 0)
			(size 0 0)
			(layers "B.Cu" "B.Mask" "B.Paste")
			(net "FT4232_CLI_EEPROM_R_SCL")
		)
		(pad "2" smd circle
			(at -0.40005 0)
			(size 0 0)
			(layers "B.Cu" "B.Mask" "B.Paste")
			(net "P3V3_AUX")
		)
	)
	(footprint ""
		(layer "B.Cu")
		(at 293.27475 -293.99992 90)
		(property "Reference" "C1623"
			(at 0 0 90)
			(layer "B.SilkS")
			(hide yes)
			(effects
				(font
					(size 1.27 1.27)
				)
				(justify mirror)
			)
		)
		(property "Value" ""
			(at 0 0 90)
			(layer "B.Fab")
			(effects
				(font
					(size 1.27 1.27)
				)
				(justify mirror)
			)
		)
		(duplicate_pad_numbers_are_jumpers no)
		(fp_line
			(start 0.299974 -0.150114)
			(end -0.299974 -0.150114)
			(stroke
				(width 0.1)
				(type default)
			)
			(layer "B.Fab")
		)
		(fp_line
			(start -0.299974 -0.150114)
			(end -0.299974 0.150114)
			(stroke
				(width 0.1)
				(type default)
			)
			(layer "B.Fab")
		)
		(fp_line
			(start 0.299974 0.150114)
			(end 0.299974 -0.150114)
			(stroke
				(width 0.1)
				(type default)
			)
			(layer "B.Fab")
		)
		(fp_line
			(start -0.299974 0.150114)
			(end 0.299974 0.150114)
			(stroke
				(width 0.1)
				(type default)
			)
			(layer "B.Fab")
		)
		(pad "1" smd rect
			(at 0.2667 0 270)
			(size 0.3048 0.381)
			(layers "B.Cu" "B.Mask" "B.Paste")
			(net "P0V8_PEX2")
		)
		(pad "2" smd rect
			(at -0.2667 0 270)
			(size 0.3048 0.381)
			(layers "B.Cu" "B.Mask" "B.Paste")
			(net "GND")
		)
	)
	(footprint ""
		(layer "B.Cu")
		(at 171.949872 -299.699934 -90)
		(property "Reference" "C1457"
			(at 0 0 90)
			(layer "B.SilkS")
			(hide yes)
			(effects
				(font
					(size 1.27 1.27)
				)
				(justify mirror)
			)
		)
		(property "Value" ""
			(at 0 0 90)
			(layer "B.Fab")
			(effects
				(font
					(size 1.27 1.27)
				)
				(justify mirror)
			)
		)
		(duplicate_pad_numbers_are_jumpers no)
		(fp_line
			(start -0.299974 0.150114)
			(end 0.299974 0.150114)
			(stroke
				(width 0.1)
				(type default)
			)
			(layer "B.Fab")
		)
		(fp_line
			(start 0.299974 0.150114)
			(end 0.299974 -0.150114)
			(stroke
				(width 0.1)
				(type default)
			)
			(layer "B.Fab")
		)
		(fp_line
			(start -0.299974 -0.150114)
			(end -0.299974 0.150114)
			(stroke
				(width 0.1)
				(type default)
			)
			(layer "B.Fab")
		)
		(fp_line
			(start 0.299974 -0.150114)
			(end -0.299974 -0.150114)
			(stroke
				(width 0.1)
				(type default)
			)
			(layer "B.Fab")
		)
		(pad "1" smd rect
			(at 0.2667 0 90)
			(size 0.3048 0.381)
			(layers "B.Cu" "B.Mask" "B.Paste")
			(net "P0V8_SERDES_VDDA_PEX1")
		)
		(pad "2" smd rect
			(at -0.2667 0 90)
			(size 0.3048 0.381)
			(layers "B.Cu" "B.Mask" "B.Paste")
			(net "GND")
		)
	)
	(footprint ""
		(layer "B.Cu")
		(at 162.7886 -298.4246)
		(property "Reference" "C3243"
			(at 0 0 0)
			(layer "B.SilkS")
			(hide yes)
			(effects
				(font
					(size 1.27 1.27)
				)
				(justify mirror)
			)
		)
		(property "Value" ""
			(at 0 0 0)
			(layer "B.Fab")
			(effects
				(font
					(size 1.27 1.27)
				)
				(justify mirror)
			)
		)
		(duplicate_pad_numbers_are_jumpers no)
		(fp_line
			(start -0.299974 -0.150114)
			(end -0.299974 0.150114)
			(stroke
				(width 0.1)
				(type default)
			)
			(layer "B.Fab")
		)
		(fp_line
			(start -0.299974 0.150114)
			(end 0.299974 0.150114)
			(stroke
				(width 0.1)
				(type default)
			)
			(layer "B.Fab")
		)
		(fp_line
			(start 0.299974 -0.150114)
			(end -0.299974 -0.150114)
			(stroke
				(width 0.1)
				(type default)
			)
			(layer "B.Fab")
		)
		(fp_line
			(start 0.299974 0.150114)
			(end 0.299974 -0.150114)
			(stroke
				(width 0.1)
				(type default)
			)
			(layer "B.Fab")
		)
		(pad "1" smd rect
			(at 0.2667 0 180)
			(size 0.3048 0.381)
			(layers "B.Cu" "B.Mask" "B.Paste")
			(net "SYSPLL_VDDA18_PEX1")
		)
		(pad "2" smd rect
			(at -0.2667 0 180)
			(size 0.3048 0.381)
			(layers "B.Cu" "B.Mask" "B.Paste")
			(net "GND")
		)
	)
	(footprint ""
		(layer "B.Cu")
		(at 173.850046 -290.199826 90)
		(property "Reference" "C1467"
			(at 0 0 90)
			(layer "B.SilkS")
			(hide yes)
			(effects
				(font
					(size 1.27 1.27)
				)
				(justify mirror)
			)
		)
		(property "Value" ""
			(at 0 0 90)
			(layer "B.Fab")
			(effects
				(font
					(size 1.27 1.27)
				)
				(justify mirror)
			)
		)
		(duplicate_pad_numbers_are_jumpers no)
		(fp_line
			(start 0.299974 -0.150114)
			(end -0.299974 -0.150114)
			(stroke
				(width 0.1)
				(type default)
			)
			(layer "B.Fab")
		)
		(fp_line
			(start -0.299974 -0.150114)
			(end -0.299974 0.150114)
			(stroke
				(width 0.1)
				(type default)
			)
			(layer "B.Fab")
		)
		(fp_line
			(start 0.299974 0.150114)
			(end 0.299974 -0.150114)
			(stroke
				(width 0.1)
				(type default)
			)
			(layer "B.Fab")
		)
		(fp_line
			(start -0.299974 0.150114)
			(end 0.299974 0.150114)
			(stroke
				(width 0.1)
				(type default)
			)
			(layer "B.Fab")
		)
		(pad "1" smd rect
			(at 0.2667 0 270)
			(size 0.3048 0.381)
			(layers "B.Cu" "B.Mask" "B.Paste")
			(net "P0V8_SERDES_VDDA_PEX1")
		)
		(pad "2" smd rect
			(at -0.2667 0 270)
			(size 0.3048 0.381)
			(layers "B.Cu" "B.Mask" "B.Paste")
			(net "GND")
		)
	)
	(footprint ""
		(layer "B.Cu")
		(at 178.599846 -299.699934 -90)
		(property "Reference" "C1481"
			(at 0 0 90)
			(layer "B.SilkS")
			(hide yes)
			(effects
				(font
					(size 1.27 1.27)
				)
				(justify mirror)
			)
		)
		(property "Value" ""
			(at 0 0 90)
			(layer "B.Fab")
			(effects
				(font
					(size 1.27 1.27)
				)
				(justify mirror)
			)
		)
		(duplicate_pad_numbers_are_jumpers no)
		(fp_line
			(start -0.299974 0.150114)
			(end 0.299974 0.150114)
			(stroke
				(width 0.1)
				(type default)
			)
			(layer "B.Fab")
		)
		(fp_line
			(start 0.299974 0.150114)
			(end 0.299974 -0.150114)
			(stroke
				(width 0.1)
				(type default)
			)
			(layer "B.Fab")
		)
		(fp_line
			(start -0.299974 -0.150114)
			(end -0.299974 0.150114)
			(stroke
				(width 0.1)
				(type default)
			)
			(layer "B.Fab")
		)
		(fp_line
			(start 0.299974 -0.150114)
			(end -0.299974 -0.150114)
			(stroke
				(width 0.1)
				(type default)
			)
			(layer "B.Fab")
		)
		(pad "1" smd rect
			(at 0.2667 0 90)
			(size 0.3048 0.381)
			(layers "B.Cu" "B.Mask" "B.Paste")
			(net "P0V8_SERDES_VDDA_PEX1")
		)
		(pad "2" smd rect
			(at -0.2667 0 90)
			(size 0.3048 0.381)
			(layers "B.Cu" "B.Mask" "B.Paste")
			(net "GND")
		)
	)
)
